(kicad_pcb
	(version 20241229)
	(generator "pcbnew")
	(generator_version "9.0")
	(general
		(thickness 1.599998)
		(legacy_teardrops no)
	)
	(paper "A4")
	(title_block
		(date "2023-02-12")
		(rev "1.1.5")
		(comment 9 "footprint 108 of 473 (U3), pads 468-484 of 484")
	)
	(layers
		(0 "F.Cu" signal)
		(4 "In1.Cu" power "In1.GND")
		(6 "In2.Cu" signal)
		(8 "In3.Cu" power "In3.GND")
		(10 "In4.Cu" power "In4.VCC")
		(12 "In5.Cu" signal)
		(14 "In6.Cu" power "In6.VCC")
		(2 "B.Cu" signal)
		(9 "F.Adhes" user "F.Adhesive")
		(11 "B.Adhes" user "B.Adhesive")
		(13 "F.Paste" user)
		(15 "B.Paste" user)
		(5 "F.SilkS" user "F.Silkscreen")
		(7 "B.SilkS" user "B.Silkscreen")
		(1 "F.Mask" user)
		(3 "B.Mask" user)
		(17 "Dwgs.User" user "User.Drawings")
		(19 "Cmts.User" user "User.Comments")
		(21 "Eco1.User" user "User.Eco1")
		(23 "Eco2.User" user "User.Eco2")
		(25 "Edge.Cuts" user)
		(27 "Margin" user)
		(31 "F.CrtYd" user "F.Courtyard")
		(29 "B.CrtYd" user "B.Courtyard")
		(35 "F.Fab" user)
		(33 "B.Fab" user)
	)
	(footprint "antmicro-footprints:BGA-484_23x23mm_Layout22x22_P1mm_FBG484"
		(locked yes)
		(layer "F.Cu")
		(at 169.036328 95.997157 -90)
		(property "Reference" "U3"
			(at -11.8 -12 270)
			(layer "F.SilkS")
			(effects
				(font
					(size 0.7 0.7)
					(thickness 0.15)
				)
				(justify left bottom)
			)
		)
		(property "Value" "XC7K70T-FBG484"
			(at -10.4 0.4 270)
			(layer "F.Fab")
			(effects
				(font
					(size 0.7 0.7)
					(thickness 0.15)
				)
				(justify left bottom)
			)
		)
		(property "Description" "Kintex®-7 Field Programmable Gate Array (FPGA) IC 285 484-BBGA, FCBGA"
			(at 0 0 270)
			(layer "F.Fab")
			(hide yes)
			(effects
				(font
					(size 1.27 1.27)
					(thickness 0.15)
				)
			)
		)
		(property "Author" "Antmicro"
			(at 73.039171 265.033485 0)
			(layer "F.Fab")
			(hide yes)
			(effects
				(font
					(size 1 1)
					(thickness 0.15)
				)
			)
		)
		(property "License" "Apache-2.0"
			(at 73.039171 265.033485 0)
			(layer "F.Fab")
			(hide yes)
			(effects
				(font
					(size 1 1)
					(thickness 0.15)
				)
			)
		)
		(property "MPN" "XC7K70T-1FBG484C"
			(at 73.039171 265.033485 0)
			(layer "F.Fab")
			(hide yes)
			(effects
				(font
					(size 1 1)
					(thickness 0.15)
				)
			)
		)
		(property "Manufacturer" "AMD-Xilinx"
			(at 73.039171 265.033485 0)
			(layer "F.Fab")
			(hide yes)
			(effects
				(font
					(size 1 1)
					(thickness 0.15)
				)
			)
		)
		(sheetname "FPGA Banks")
		(sheetfile "fpga-banks.kicad_sch")
		(attr smd)
		(pad "Y6" smd circle
			(at -5.5 8.5 270)
			(size 0.51 0.51)
			(layers "F.Cu" "F.Mask" "F.Paste")
			(net 540 "unconnected-(U3E-IO_L7N_T1_33-PadY6)")
			(pinfunction "IO_L7N_T1_33")
			(pintype "bidirectional+no_connect")
		)
		(pad "Y7" smd circle
			(at -4.5 8.5 270)
			(size 0.51 0.51)
			(layers "F.Cu" "F.Mask" "F.Paste")
			(net 542 "unconnected-(U3E-IO_L12N_T1_MRCC_33-PadY7)")
			(pinfunction "IO_L12N_T1_MRCC_33")
			(pintype "bidirectional+no_connect")
		)
		(pad "Y8" smd circle
			(at -3.5 8.5 270)
			(size 0.51 0.51)
			(layers "F.Cu" "F.Mask" "F.Paste")
			(net 543 "unconnected-(U3E-IO_L12P_T1_MRCC_33-PadY8)")
			(pinfunction "IO_L12P_T1_MRCC_33")
			(pintype "bidirectional+no_connect")
		)
		(pad "Y9" smd circle
			(at -2.5 8.5 270)
			(size 0.51 0.51)
			(layers "F.Cu" "F.Mask" "F.Paste")
			(net 544 "unconnected-(U3E-IO_L13N_T2_MRCC_33-PadY9)")
			(pinfunction "IO_L13N_T2_MRCC_33")
			(pintype "bidirectional+no_connect")
		)
		(pad "Y10" smd circle
			(at -1.5 8.5 270)
			(size 0.51 0.51)
			(layers "F.Cu" "F.Mask" "F.Paste")
			(net 66 "VDDQ")
			(pinfunction "VCCO_33")
			(pintype "passive")
		)
		(pad "Y11" smd circle
			(at -0.5 8.5 270)
			(size 0.51 0.51)
			(layers "F.Cu" "F.Mask" "F.Paste")
			(net 482 "IO_Y11")
			(pinfunction "IO_L6N_T0_VREF_33")
			(pintype "bidirectional")
		)
		(pad "Y12" smd circle
			(at 0.5 8.5 270)
			(size 0.51 0.51)
			(layers "F.Cu" "F.Mask" "F.Paste")
			(net 484 "IO_Y12")
			(pinfunction "IO_L19N_T3_VREF_33")
			(pintype "bidirectional")
		)
		(pad "Y13" smd circle
			(at 1.5 8.5 270)
			(size 0.51 0.51)
			(layers "F.Cu" "F.Mask" "F.Paste")
			(net 545 "unconnected-(U3E-IO_L21P_T3_DQS_33-PadY13)")
			(pinfunction "IO_L21P_T3_DQS_33")
			(pintype "bidirectional+no_connect")
		)
		(pad "Y14" smd circle
			(at 2.5 8.5 270)
			(size 0.51 0.51)
			(layers "F.Cu" "F.Mask" "F.Paste")
			(net 495 "HR_DQ4")
			(pinfunction "IO_L22N_T3_13")
			(pintype "bidirectional")
		)
		(pad "Y15" smd circle
			(at 3.5 8.5 270)
			(size 0.51 0.51)
			(layers "F.Cu" "F.Mask" "F.Paste")
			(net 5 "GND")
			(pinfunction "GND")
			(pintype "passive")
		)
		(pad "Y16" smd circle
			(at 4.5 8.5 270)
			(size 0.51 0.51)
			(layers "F.Cu" "F.Mask" "F.Paste")
			(net 497 "HR_DQ6")
			(pinfunction "IO_L21N_T3_DQS_13")
			(pintype "bidirectional")
		)
		(pad "Y17" smd circle
			(at 5.5 8.5 270)
			(size 0.51 0.51)
			(layers "F.Cu" "F.Mask" "F.Paste")
			(net 492 "HR_RW")
			(pinfunction "IO_L14N_T2_SRCC_13")
			(pintype "bidirectional")
		)
		(pad "Y18" smd circle
			(at 6.5 8.5 270)
			(size 0.51 0.51)
			(layers "F.Cu" "F.Mask" "F.Paste")
			(net 546 "unconnected-(U3I-IO_L13P_T2_MRCC_13-PadY18)")
			(pinfunction "IO_L13P_T2_MRCC_13")
			(pintype "bidirectional+no_connect")
		)
		(pad "Y19" smd circle
			(at 7.5 8.5 270)
			(size 0.51 0.51)
			(layers "F.Cu" "F.Mask" "F.Paste")
			(net 547 "unconnected-(U3I-IO_L13N_T2_MRCC_13-PadY19)")
			(pinfunction "IO_L13N_T2_MRCC_13")
			(pintype "bidirectional+no_connect")
		)
		(pad "Y20" smd circle
			(at 8.5 8.5 270)
			(size 0.51 0.51)
			(layers "F.Cu" "F.Mask" "F.Paste")
			(net 459 "3V3_SYS")
			(pinfunction "VCCO_13")
			(pintype "passive")
		)
		(pad "Y21" smd circle
			(at 9.5 8.5 270)
			(size 0.51 0.51)
			(layers "F.Cu" "F.Mask" "F.Paste")
			(net 447 "AUX_JTAG_TMS")
			(pinfunction "IO_L7P_T1_13")
			(pintype "bidirectional")
		)
		(pad "Y22" smd circle
			(at 10.5 8.5 270)
			(size 0.51 0.51)
			(layers "F.Cu" "F.Mask" "F.Paste")
			(net 548 "unconnected-(U3I-IO_L7N_T1_13-PadY22)")
			(pinfunction "IO_L7N_T1_13")
			(pintype "bidirectional+no_connect")
		)
	)
)
